# S9S_MB_2U (Grand Teton) — schematic netlist excerpt (pin names and nets, part order shuffled) for the footprints in the layout excerpt that follows; sources: Cadence DE-HDL packaged netlist, KiCad conversion of 03242023_DA0F0TMBIJ0_F0T_Motherboard_J_brd_V01_OCP.brd

R4563  Q_RES  33.2 1% CHIP  pkg 0402LF  page 215 : A = SWB_HSC_PWRGD_ISO_R ; B = SWB_HSC_PWRGD_ISO
PR187  Q_RES  10K 0.1% CHIP  pkg 0402LF  page 262 : A = P1V05_PCH_AUX_FB ; B = SH_P1V05_PCH_AUX_N

(kicad_pcb
	(version 20260206)
	(generator "pcbnew")
	(generator_version "10.0")
	(general
		(thickness 1.6)
		(legacy_teardrops no)
	)
	(paper "A4")
	(title_block
		(title "03242023_DA0F0TMBIJ0_F0T_Motherboard_J_brd_V01_OCP.brd")
		(comment 1 "Grand Teton / footprints 2598-2599 of 6105")
	)
	(layers
		(0 "F.Cu" signal "TOP")
		(4 "In1.Cu" signal "GND")
		(6 "In2.Cu" signal "IN1")
		(8 "In3.Cu" signal "GND1")
		(10 "In4.Cu" signal "IN2")
		(12 "In5.Cu" signal "GND2")
		(14 "In6.Cu" signal "IN3")
		(16 "In7.Cu" signal "GND3")
		(18 "In8.Cu" signal "VCC")
		(20 "In9.Cu" signal "VCC1")
		(22 "In10.Cu" signal "GND4")
		(24 "In11.Cu" signal "IN4")
		(26 "In12.Cu" signal "GND5")
		(28 "In13.Cu" signal "IN5")
		(30 "In14.Cu" signal "GND6")
		(32 "In15.Cu" signal "IN6")
		(34 "In16.Cu" signal "GND7")
		(2 "B.Cu" signal "BOTTOM")
		(9 "F.Adhes" user "F.Adhesive")
		(11 "B.Adhes" user "B.Adhesive")
		(13 "F.Paste" user "Package Geometry/Pastemask Top")
		(15 "B.Paste" user "Package Geometry/Pastemask Bottom")
		(5 "F.SilkS" user "Ref Des/Silkscreen Top")
		(7 "B.SilkS" user "Ref Des/Silkscreen Bottom")
		(1 "F.Mask" user "Board Geometry/Soldermask Top")
		(3 "B.Mask" user "Board Geometry/Soldermask Bottom")
		(17 "Dwgs.User" user "User.Drawings")
		(19 "Cmts.User" user "User.Comments")
		(21 "Eco1.User" user "User.Eco1")
		(23 "Eco2.User" user "User.Eco2")
		(25 "Edge.Cuts" user "Board Geometry/Outline")
		(27 "Margin" user)
		(31 "F.CrtYd" user "Package Geometry/Place Bound Top")
		(29 "B.CrtYd" user "Package Geometry/Place Bound Bottom")
		(35 "F.Fab" user "Ref Des/Assembly Top")
		(33 "B.Fab" user "Ref Des/Assembly Bottom")
	)
	(footprint ""
		(layer "F.Cu")
		(at 260.561582 -75.505056)
		(property "Reference" "PR187"
			(at 0 0 0)
			(layer "F.SilkS")
			(hide yes)
			(effects
				(font
					(size 1.27 1.27)
				)
			)
		)
		(property "Value" ""
			(at 0 0 0)
			(layer "F.Fab")
			(effects
				(font
					(size 1.27 1.27)
				)
			)
		)
		(duplicate_pad_numbers_are_jumpers no)
		(fp_line
			(start -0.7874 -0.4064)
			(end 0.7874 -0.4064)
			(stroke
				(width 0.1524)
				(type default)
			)
			(layer "F.SilkS")
		)
		(fp_line
			(start -0.7874 0.4064)
			(end -0.7874 -0.4064)
			(stroke
				(width 0.1524)
				(type default)
			)
			(layer "F.SilkS")
		)
		(fp_line
			(start 0.7874 -0.4064)
			(end 0.7874 0.4064)
			(stroke
				(width 0.1524)
				(type default)
			)
			(layer "F.SilkS")
		)
		(fp_line
			(start 0.7874 0.4064)
			(end -0.7874 0.4064)
			(stroke
				(width 0.1524)
				(type default)
			)
			(layer "F.SilkS")
		)
		(fp_line
			(start -0.67945 -0.305054)
			(end -0.12065 -0.305054)
			(stroke
				(width 0.1)
				(type default)
			)
			(layer "F.Fab")
		)
		(fp_line
			(start -0.67945 0.3048)
			(end -0.67945 -0.305054)
			(stroke
				(width 0.1)
				(type default)
			)
			(layer "F.Fab")
		)
		(fp_line
			(start -0.12065 -0.305054)
			(end -0.12065 -0.2794)
			(stroke
				(width 0.1)
				(type default)
			)
			(layer "F.Fab")
		)
		(fp_line
			(start -0.12065 -0.2794)
			(end 0.12065 -0.2794)
			(stroke
				(width 0.1)
				(type default)
			)
			(layer "F.Fab")
		)
		(fp_line
			(start -0.12065 0.2794)
			(end -0.12065 0.3048)
			(stroke
				(width 0.1)
				(type default)
			)
			(layer "F.Fab")
		)
		(fp_line
			(start -0.12065 0.3048)
			(end -0.67945 0.3048)
			(stroke
				(width 0.1)
				(type default)
			)
			(layer "F.Fab")
		)
		(fp_line
			(start 0.120396 0.2794)
			(end -0.12065 0.2794)
			(stroke
				(width 0.1)
				(type default)
			)
			(layer "F.Fab")
		)
		(fp_line
			(start 0.120396 0.3048)
			(end 0.120396 0.2794)
			(stroke
				(width 0.1)
				(type default)
			)
			(layer "F.Fab")
		)
		(fp_line
			(start 0.12065 -0.3048)
			(end 0.67945 -0.3048)
			(stroke
				(width 0.1)
				(type default)
			)
			(layer "F.Fab")
		)
		(fp_line
			(start 0.12065 -0.2794)
			(end 0.12065 -0.3048)
			(stroke
				(width 0.1)
				(type default)
			)
			(layer "F.Fab")
		)
		(fp_line
			(start 0.67945 -0.3048)
			(end 0.67945 0.3048)
			(stroke
				(width 0.1)
				(type default)
			)
			(layer "F.Fab")
		)
		(fp_line
			(start 0.67945 0.3048)
			(end 0.120396 0.3048)
			(stroke
				(width 0.1)
				(type default)
			)
			(layer "F.Fab")
		)
		(pad "1" smd circle
			(at -0.40005 0)
			(size 0 0)
			(layers "F.Cu" "F.Mask" "F.Paste")
			(net "P1V05_PCH_AUX_FB")
		)
		(pad "2" smd circle
			(at 0.40005 0)
			(size 0 0)
			(layers "F.Cu" "F.Mask" "F.Paste")
			(net "SH_P1V05_PCH_AUX_N")
		)
	)
	(footprint ""
		(layer "F.Cu")
		(at 356.616 -413.095948)
		(property "Reference" "R4563"
			(at 0 0 0)
			(layer "F.SilkS")
			(hide yes)
			(effects
				(font
					(size 1.27 1.27)
				)
			)
		)
		(property "Value" ""
			(at 0 0 0)
			(layer "F.Fab")
			(effects
				(font
					(size 1.27 1.27)
				)
			)
		)
		(duplicate_pad_numbers_are_jumpers no)
		(fp_line
			(start -0.7874 -0.4064)
			(end 0.7874 -0.4064)
			(stroke
				(width 0.1524)
				(type default)
			)
			(layer "F.SilkS")
		)
		(fp_line
			(start -0.7874 0.4064)
			(end -0.7874 -0.4064)
			(stroke
				(width 0.1524)
				(type default)
			)
			(layer "F.SilkS")
		)
		(fp_line
			(start 0.7874 -0.4064)
			(end 0.7874 0.4064)
			(stroke
				(width 0.1524)
				(type default)
			)
			(layer "F.SilkS")
		)
		(fp_line
			(start 0.7874 0.4064)
			(end -0.7874 0.4064)
			(stroke
				(width 0.1524)
				(type default)
			)
			(layer "F.SilkS")
		)
		(fp_line
			(start -0.67945 -0.305054)
			(end -0.12065 -0.305054)
			(stroke
				(width 0.1)
				(type default)
			)
			(layer "F.Fab")
		)
		(fp_line
			(start -0.67945 0.3048)
			(end -0.67945 -0.305054)
			(stroke
				(width 0.1)
				(type default)
			)
			(layer "F.Fab")
		)
		(fp_line
			(start -0.12065 -0.305054)
			(end -0.12065 -0.2794)
			(stroke
				(width 0.1)
				(type default)
			)
			(layer "F.Fab")
		)
		(fp_line
			(start -0.12065 -0.2794)
			(end 0.12065 -0.2794)
			(stroke
				(width 0.1)
				(type default)
			)
			(layer "F.Fab")
		)
		(fp_line
			(start -0.12065 0.2794)
			(end -0.12065 0.3048)
			(stroke
				(width 0.1)
				(type default)
			)
			(layer "F.Fab")
		)
		(fp_line
			(start -0.12065 0.3048)
			(end -0.67945 0.3048)
			(stroke
				(width 0.1)
				(type default)
			)
			(layer "F.Fab")
		)
		(fp_line
			(start 0.120396 0.2794)
			(end -0.12065 0.2794)
			(stroke
				(width 0.1)
				(type default)
			)
			(layer "F.Fab")
		)
		(fp_line
			(start 0.120396 0.3048)
			(end 0.120396 0.2794)
			(stroke
				(width 0.1)
				(type default)
			)
			(layer "F.Fab")
		)
		(fp_line
			(start 0.12065 -0.3048)
			(end 0.67945 -0.3048)
			(stroke
				(width 0.1)
				(type default)
			)
			(layer "F.Fab")
		)
		(fp_line
			(start 0.12065 -0.2794)
			(end 0.12065 -0.3048)
			(stroke
				(width 0.1)
				(type default)
			)
			(layer "F.Fab")
		)
		(fp_line
			(start 0.67945 -0.3048)
			(end 0.67945 0.3048)
			(stroke
				(width 0.1)
				(type default)
			)
			(layer "F.Fab")
		)
		(fp_line
			(start 0.67945 0.3048)
			(end 0.120396 0.3048)
			(stroke
				(width 0.1)
				(type default)
			)
			(layer "F.Fab")
		)
		(pad "1" smd circle
			(at -0.40005 0)
			(size 0 0)
			(layers "F.Cu" "F.Mask" "F.Paste")
			(net "SWB_HSC_PWRGD_ISO_R")
		)
		(pad "2" smd circle
			(at 0.40005 0)
			(size 0 0)
			(layers "F.Cu" "F.Mask" "F.Paste")
			(net "SWB_HSC_PWRGD_ISO")
		)
	)
)
